# BASEBOARD_FAB2 (Tioga Pass) — schematic netlist excerpt (pin names and nets, part order shuffled) for the footprints in the layout excerpt that follows; sources: Cadence DE-HDL packaged netlist, KiCad conversion of Wiwynn_Tioga_Pass_MB.brd

R7B18  RES  1.0K 0.1% CHIP  pkg 0402  page 232 : A = VSENSE_PVPP_DEF ; B = VR_COMP_PVPP_DEF

Q9G1  FET_N_DUAL  NTJD4001N FET  pkg SMLF  page 169
  SOURCE(0)  = GND
  GATE(0)  = FM_BATTERY_SENSE_EN_N
  DRAIN(0)  = P3V_BAT_SOURCE_R
  SOURCE(0)  = A_P3V_BAT_SCALED
  GATE(0)  = FM_BATTERY_SENSE_EN
  DRAIN(0)  = FM_BATTERY_SENSE_EN

(kicad_pcb
	(version 20260206)
	(generator "pcbnew")
	(generator_version "10.0")
	(general
		(thickness 1.6)
		(legacy_teardrops no)
	)
	(paper "A4")
	(title_block
		(title "Wiwynn_Tioga_Pass_MB.brd")
		(comment 1 "Tioga Pass / footprints 969-970 of 4770")
	)
	(layers
		(0 "F.Cu" signal "TOP")
		(4 "In1.Cu" signal "L2GND")
		(6 "In2.Cu" signal "L3")
		(8 "In3.Cu" signal "L4GND")
		(10 "In4.Cu" signal "L5")
		(12 "In5.Cu" signal "L6GND")
		(14 "In6.Cu" signal "L7VCC")
		(16 "In7.Cu" signal "L8VCC")
		(18 "In8.Cu" signal "L9GND")
		(20 "In9.Cu" signal "L10")
		(22 "In10.Cu" signal "L11GND")
		(24 "In11.Cu" signal "L12")
		(26 "In12.Cu" signal "L13GND")
		(2 "B.Cu" signal "BOTTOM")
		(9 "F.Adhes" user "F.Adhesive")
		(11 "B.Adhes" user "B.Adhesive")
		(13 "F.Paste" user "Package Geometry/Pastemask Top")
		(15 "B.Paste" user "Package Geometry/Pastemask Bottom")
		(5 "F.SilkS" user "Ref Des/Silkscreen Top")
		(7 "B.SilkS" user "Ref Des/Silkscreen Bottom")
		(1 "F.Mask" user "Board Geometry/Soldermask Top")
		(3 "B.Mask" user "Board Geometry/Soldermask Bottom")
		(17 "Dwgs.User" user "User.Drawings")
		(19 "Cmts.User" user "User.Comments")
		(21 "Eco1.User" user "User.Eco1")
		(23 "Eco2.User" user "User.Eco2")
		(25 "Edge.Cuts" user "Board Geometry/Outline")
		(27 "Margin" user)
		(31 "F.CrtYd" user "Package Geometry/Place Bound Top")
		(29 "B.CrtYd" user "Package Geometry/Place Bound Bottom")
		(35 "F.Fab" user "Ref Des/Assembly Top")
		(33 "B.Fab" user "Ref Des/Assembly Bottom")
	)
	(footprint ""
		(layer "F.Cu")
		(at 337.1215 -127.254 90)
		(property "Reference" "R7B18"
			(at 0 0 90)
			(layer "F.SilkS")
			(hide yes)
			(effects
				(font
					(size 1.27 1.27)
				)
			)
		)
		(property "Value" ""
			(at 0 0 90)
			(layer "F.Fab")
			(effects
				(font
					(size 1.27 1.27)
				)
			)
		)
		(duplicate_pad_numbers_are_jumpers no)
		(fp_poly
			(pts
				(xy -0.2794 -0.1016) (xy 0.2794 -0.1016) (xy 0.2794 0.9906) (xy -0.2794 0.9906)
			)
			(stroke
				(width 0)
				(type default)
			)
			(fill no)
			(layer "F.CrtYd")
		)
		(fp_line
			(start 0.2794 -0.1016)
			(end -0.2794 -0.1016)
			(stroke
				(width 0.1)
				(type default)
			)
			(layer "F.Fab")
		)
		(fp_line
			(start -0.2794 -0.1016)
			(end -0.2794 0.9906)
			(stroke
				(width 0.1)
				(type default)
			)
			(layer "F.Fab")
		)
		(fp_line
			(start 0.2794 0.9906)
			(end 0.2794 -0.1016)
			(stroke
				(width 0.1)
				(type default)
			)
			(layer "F.Fab")
		)
		(fp_line
			(start -0.2794 0.9906)
			(end 0.2794 0.9906)
			(stroke
				(width 0.1)
				(type default)
			)
			(layer "F.Fab")
		)
		(pad "1" smd rect
			(at 0 0 90)
			(size 0.508 0.508)
			(layers "F.Cu" "F.Mask" "F.Paste")
			(net "VSENSE_PVPP_DEF")
		)
		(pad "2" smd rect
			(at 0 0.889 90)
			(size 0.508 0.508)
			(layers "F.Cu" "F.Mask" "F.Paste")
			(net "VR_COMP_PVPP_DEF")
		)
		(zone
			(layer "F.Cu")
			(hatch none 0.5)
			(connect_pads
				(clearance 0)
			)
			(min_thickness 0.25)
			(keepout
				(tracks allowed)
				(vias not_allowed)
				(pads allowed)
				(copperpour not_allowed)
				(footprints allowed)
			)
			(placement
				(enabled no)
				(sheetname "")
			)
			(fill
				(thermal_gap 0.5)
				(thermal_bridge_width 0.5)
				(island_removal_mode 0)
			)
			(polygon
				(pts
					(xy 337.3755 -127) (xy 337.3755 -127.508) (xy 337.7565 -127.508) (xy 337.7565 -127)
				)
			)
		)
		(zone
			(layer "F.Cu")
			(hatch none 0.5)
			(connect_pads
				(clearance 0)
			)
			(min_thickness 0.25)
			(keepout
				(tracks not_allowed)
				(vias allowed)
				(pads allowed)
				(copperpour not_allowed)
				(footprints allowed)
			)
			(placement
				(enabled no)
				(sheetname "")
			)
			(fill
				(thermal_gap 0.5)
				(thermal_bridge_width 0.5)
				(island_removal_mode 0)
			)
			(polygon
				(pts
					(xy 337.7565 -127) (xy 337.7565 -127.508) (xy 337.3755 -127.508) (xy 337.3755 -127)
				)
			)
		)
	)
	(footprint ""
		(layer "F.Cu")
		(at 466.311996 2.8194 180)
		(property "Reference" "Q9G1"
			(at 2.54254 2.20091 0)
			(unlocked yes)
			(layer "F.SilkS")
			(effects
				(font
					(size 0.7874 0.5842)
					(thickness 0.1524)
				)
				(justify left)
			)
		)
		(property "Value" ""
			(at 0 0 180)
			(layer "F.Fab")
			(effects
				(font
					(size 1.27 1.27)
				)
			)
		)
		(duplicate_pad_numbers_are_jumpers no)
		(fp_circle
			(center -0.48641 -0.538734)
			(end -0.61341 -0.538734)
			(stroke
				(width 0.254)
				(type default)
			)
			(fill no)
			(layer "F.SilkS")
		)
		(fp_poly
			(pts
				(xy 0.2159 1.7526) (xy 1.5621 1.7526) (xy 1.5621 -0.4572) (xy 0.2159 -0.4572)
			)
			(stroke
				(width 0)
				(type default)
			)
			(fill no)
			(layer "F.CrtYd")
		)
		(fp_line
			(start 1.5621 1.75514)
			(end 1.5621 -0.45466)
			(stroke
				(width 0.1)
				(type default)
			)
			(layer "F.Fab")
		)
		(fp_line
			(start 1.5621 -0.45466)
			(end 0.2159 -0.45466)
			(stroke
				(width 0.1)
				(type default)
			)
			(layer "F.Fab")
		)
		(fp_line
			(start 0.2159 1.75514)
			(end 1.5621 1.75514)
			(stroke
				(width 0.1)
				(type default)
			)
			(layer "F.Fab")
		)
		(fp_line
			(start 0.2159 -0.45466)
			(end 0.2159 1.75514)
			(stroke
				(width 0.1)
				(type default)
			)
			(layer "F.Fab")
		)
		(fp_circle
			(center -0.508 -0.7874)
			(end -0.635 -0.7874)
			(stroke
				(width 0.254)
				(type default)
			)
			(fill no)
			(layer "F.Fab")
		)
		(pad "1" smd rect
			(at 0 0 180)
			(size 1.016 0.381)
			(layers "F.Cu" "F.Mask" "F.Paste")
			(net "GND")
		)
		(pad "2" smd rect
			(at 0 0.65024 180)
			(size 1.016 0.381)
			(layers "F.Cu" "F.Mask" "F.Paste")
			(net "FM_BATTERY_SENSE_EN_N")
		)
		(pad "3" smd rect
			(at 0 1.30048 180)
			(size 1.016 0.381)
			(layers "F.Cu" "F.Mask" "F.Paste")
			(net "P3V_BAT_SOURCE_R")
		)
		(pad "4" smd rect
			(at 1.778 1.30048 180)
			(size 1.016 0.381)
			(layers "F.Cu" "F.Mask" "F.Paste")
			(net "A_P3V_BAT_SCALED")
		)
		(pad "5" smd rect
			(at 1.778 0.65024 180)
			(size 1.016 0.381)
			(layers "F.Cu" "F.Mask" "F.Paste")
			(net "FM_BATTERY_SENSE_EN")
		)
		(pad "6" smd rect
			(at 1.778 0 180)
			(size 1.016 0.381)
			(layers "F.Cu" "F.Mask" "F.Paste")
			(net "FM_BATTERY_SENSE_EN")
		)
		(zone
			(layer "F.Cu")
			(hatch none 0.5)
			(connect_pads
				(clearance 0)
			)
			(min_thickness 0.25)
			(keepout
				(tracks allowed)
				(vias not_allowed)
				(pads allowed)
				(copperpour not_allowed)
				(footprints allowed)
			)
			(placement
				(enabled no)
				(sheetname "")
			)
			(fill
				(thermal_gap 0.5)
				(thermal_bridge_width 0.5)
				(island_removal_mode 0)
			)
			(polygon
				(pts
					(xy 465.041996 3.0099) (xy 464.025996 3.0099) (xy 464.025996 1.3208) (xy 465.041996 1.3208)
				)
			)
		)
		(zone
			(layer "F.Cu")
			(hatch none 0.5)
			(connect_pads
				(clearance 0)
			)
			(min_thickness 0.25)
			(keepout
				(tracks allowed)
				(vias not_allowed)
				(pads allowed)
				(copperpour not_allowed)
				(footprints allowed)
			)
			(placement
				(enabled no)
				(sheetname "")
			)
			(fill
				(thermal_gap 0.5)
				(thermal_bridge_width 0.5)
				(island_removal_mode 0)
			)
			(polygon
				(pts
					(xy 466.819996 3.0099) (xy 465.803996 3.0099) (xy 465.803996 1.3208) (xy 466.819996 1.3208)
				)
			)
		)
	)
)
